(kicad_pcb
	(version 20260206)
	(generator "pcbnew")
	(generator_version "10.0")
	(general
		(thickness 1.6)
		(legacy_teardrops no)
	)
	(paper "A4")
	(title_block
		(title "04192023_DAF0TMB3IC0_F0TG_MB_C_brd_V02_OCP.brd")
		(comment 1 "Grand Teton / footprints 5414-5420 of 8354")
	)
	(layers
		(0 "F.Cu" signal "TOP")
		(4 "In1.Cu" signal "GND")
		(6 "In2.Cu" signal "IN1")
		(8 "In3.Cu" signal "GND1")
		(10 "In4.Cu" signal "IN2")
		(12 "In5.Cu" signal "GND2")
		(14 "In6.Cu" signal "IN3")
		(16 "In7.Cu" signal "GND3")
		(18 "In8.Cu" signal "VCC")
		(20 "In9.Cu" signal "VCC1")
		(22 "In10.Cu" signal "GND4")
		(24 "In11.Cu" signal "IN4")
		(26 "In12.Cu" signal "GND5")
		(28 "In13.Cu" signal "IN5")
		(30 "In14.Cu" signal "GND6")
		(32 "In15.Cu" signal "IN6")
		(34 "In16.Cu" signal "GND7")
		(2 "B.Cu" signal "BOTTOM")
		(9 "F.Adhes" user "F.Adhesive")
		(11 "B.Adhes" user "B.Adhesive")
		(13 "F.Paste" user "Package Geometry/Pastemask Top")
		(15 "B.Paste" user "Package Geometry/Pastemask Bottom")
		(5 "F.SilkS" user "Ref Des/Silkscreen Top")
		(7 "B.SilkS" user "Ref Des/Silkscreen Bottom")
		(1 "F.Mask" user "Board Geometry/Soldermask Top")
		(3 "B.Mask" user "Board Geometry/Soldermask Bottom")
		(17 "Dwgs.User" user "User.Drawings")
		(19 "Cmts.User" user "User.Comments")
		(21 "Eco1.User" user "User.Eco1")
		(23 "Eco2.User" user "User.Eco2")
		(25 "Edge.Cuts" user "Board Geometry/Outline")
		(27 "Margin" user)
		(31 "F.CrtYd" user "Package Geometry/Place Bound Top")
		(29 "B.CrtYd" user "Package Geometry/Place Bound Bottom")
		(35 "F.Fab" user "Ref Des/Assembly Top")
		(33 "B.Fab" user "Ref Des/Assembly Bottom")
	)
	(footprint ""
		(layer "B.Cu")
		(at 237.896654 -322.511166)
		(property "Reference" "R1237"
			(at 0 0 0)
			(layer "B.SilkS")
			(hide yes)
			(effects
				(font
					(size 1.27 1.27)
				)
				(justify mirror)
			)
		)
		(property "Value" ""
			(at 0 0 0)
			(layer "B.Fab")
			(effects
				(font
					(size 1.27 1.27)
				)
				(justify mirror)
			)
		)
		(duplicate_pad_numbers_are_jumpers no)
		(fp_line
			(start -0.7874 -0.4064)
			(end -0.7874 0.4064)
			(stroke
				(width 0.1524)
				(type default)
			)
			(layer "B.SilkS")
		)
		(fp_line
			(start -0.7874 0.4064)
			(end 0.7874 0.4064)
			(stroke
				(width 0.1524)
				(type default)
			)
			(layer "B.SilkS")
		)
		(fp_line
			(start 0.7874 -0.4064)
			(end -0.7874 -0.4064)
			(stroke
				(width 0.1524)
				(type default)
			)
			(layer "B.SilkS")
		)
		(fp_line
			(start 0.7874 0.4064)
			(end 0.7874 -0.4064)
			(stroke
				(width 0.1524)
				(type default)
			)
			(layer "B.SilkS")
		)
		(fp_line
			(start -0.67945 -0.3048)
			(end -0.67945 0.3048)
			(stroke
				(width 0.1)
				(type default)
			)
			(layer "B.Fab")
		)
		(fp_line
			(start -0.67945 0.3048)
			(end -0.120396 0.3048)
			(stroke
				(width 0.1)
				(type default)
			)
			(layer "B.Fab")
		)
		(fp_line
			(start -0.12065 -0.3048)
			(end -0.67945 -0.3048)
			(stroke
				(width 0.1)
				(type default)
			)
			(layer "B.Fab")
		)
		(fp_line
			(start -0.12065 -0.2794)
			(end -0.12065 -0.3048)
			(stroke
				(width 0.1)
				(type default)
			)
			(layer "B.Fab")
		)
		(fp_line
			(start -0.120396 0.2794)
			(end 0.12065 0.2794)
			(stroke
				(width 0.1)
				(type default)
			)
			(layer "B.Fab")
		)
		(fp_line
			(start -0.120396 0.3048)
			(end -0.120396 0.2794)
			(stroke
				(width 0.1)
				(type default)
			)
			(layer "B.Fab")
		)
		(fp_line
			(start 0.12065 -0.305054)
			(end 0.12065 -0.2794)
			(stroke
				(width 0.1)
				(type default)
			)
			(layer "B.Fab")
		)
		(fp_line
			(start 0.12065 -0.2794)
			(end -0.12065 -0.2794)
			(stroke
				(width 0.1)
				(type default)
			)
			(layer "B.Fab")
		)
		(fp_line
			(start 0.12065 0.2794)
			(end 0.12065 0.3048)
			(stroke
				(width 0.1)
				(type default)
			)
			(layer "B.Fab")
		)
		(fp_line
			(start 0.12065 0.3048)
			(end 0.67945 0.3048)
			(stroke
				(width 0.1)
				(type default)
			)
			(layer "B.Fab")
		)
		(fp_line
			(start 0.67945 -0.305054)
			(end 0.12065 -0.305054)
			(stroke
				(width 0.1)
				(type default)
			)
			(layer "B.Fab")
		)
		(fp_line
			(start 0.67945 0.3048)
			(end 0.67945 -0.305054)
			(stroke
				(width 0.1)
				(type default)
			)
			(layer "B.Fab")
		)
		(pad "1" smd circle
			(at 0.40005 0 180)
			(size 0 0)
			(layers "B.Cu" "B.Mask" "B.Paste")
			(net "P1V8_AUX")
		)
		(pad "2" smd circle
			(at -0.40005 0 180)
			(size 0 0)
			(layers "B.Cu" "B.Mask" "B.Paste")
			(net "P1V8_AUX_ADC")
		)
	)
	(footprint ""
		(layer "B.Cu")
		(at 329.95108 -335.055972 90)
		(property "Reference" "PC90_2"
			(at 0 0 90)
			(layer "B.SilkS")
			(hide yes)
			(effects
				(font
					(size 1.27 1.27)
				)
				(justify mirror)
			)
		)
		(property "Value" ""
			(at 0 0 90)
			(layer "B.Fab")
			(effects
				(font
					(size 1.27 1.27)
				)
				(justify mirror)
			)
		)
		(duplicate_pad_numbers_are_jumpers no)
		(fp_line
			(start 1.524 -0.762)
			(end -1.524 -0.762)
			(stroke
				(width 0.1524)
				(type default)
			)
			(layer "B.SilkS")
		)
		(fp_line
			(start -1.524 -0.762)
			(end -1.524 0.762)
			(stroke
				(width 0.1524)
				(type default)
			)
			(layer "B.SilkS")
		)
		(fp_line
			(start 1.524 0.762)
			(end 1.524 -0.762)
			(stroke
				(width 0.1524)
				(type default)
			)
			(layer "B.SilkS")
		)
		(fp_line
			(start -1.524 0.762)
			(end 1.524 0.762)
			(stroke
				(width 0.1524)
				(type default)
			)
			(layer "B.SilkS")
		)
		(fp_line
			(start 1.1049 -0.724916)
			(end 1.1049 0.724916)
			(stroke
				(width 0.1)
				(type default)
			)
			(layer "B.Fab")
		)
		(fp_line
			(start -1.1049 -0.724916)
			(end 1.1049 -0.724916)
			(stroke
				(width 0.1)
				(type default)
			)
			(layer "B.Fab")
		)
		(fp_line
			(start 1.1049 0.724916)
			(end -1.1049 0.724916)
			(stroke
				(width 0.1)
				(type default)
			)
			(layer "B.Fab")
		)
		(fp_line
			(start -1.1049 0.724916)
			(end -1.1049 -0.724916)
			(stroke
				(width 0.1)
				(type default)
			)
			(layer "B.Fab")
		)
		(pad "1" smd rect
			(at 0.889 0 90)
			(size 1.016 1.27)
			(layers "B.Cu" "B.Mask" "B.Paste")
			(net "SW_P12V_AUX_PVDDCR_CPU1_P0_FLT")
		)
		(pad "2" smd rect
			(at -0.889 0 90)
			(size 1.016 1.27)
			(layers "B.Cu" "B.Mask" "B.Paste")
			(net "GND")
		)
	)
	(footprint ""
		(layer "B.Cu")
		(at 169.66692 -53.431948 180)
		(property "Reference" "C1923"
			(at 0 0 0)
			(layer "B.SilkS")
			(hide yes)
			(effects
				(font
					(size 1.27 1.27)
				)
				(justify mirror)
			)
		)
		(property "Value" ""
			(at 0 0 0)
			(layer "B.Fab")
			(effects
				(font
					(size 1.27 1.27)
				)
				(justify mirror)
			)
		)
		(duplicate_pad_numbers_are_jumpers no)
		(fp_line
			(start 0.7874 0.4064)
			(end 0.7874 -0.4064)
			(stroke
				(width 0.1524)
				(type default)
			)
			(layer "B.SilkS")
		)
		(fp_line
			(start 0.7874 -0.4064)
			(end -0.7874 -0.4064)
			(stroke
				(width 0.1524)
				(type default)
			)
			(layer "B.SilkS")
		)
		(fp_line
			(start -0.7874 0.4064)
			(end 0.7874 0.4064)
			(stroke
				(width 0.1524)
				(type default)
			)
			(layer "B.SilkS")
		)
		(fp_line
			(start -0.7874 -0.4064)
			(end -0.7874 0.4064)
			(stroke
				(width 0.1524)
				(type default)
			)
			(layer "B.SilkS")
		)
		(fp_line
			(start 0.67945 0.3048)
			(end 0.67945 -0.305054)
			(stroke
				(width 0.1)
				(type default)
			)
			(layer "B.Fab")
		)
		(fp_line
			(start 0.67945 -0.305054)
			(end 0.12065 -0.305054)
			(stroke
				(width 0.1)
				(type default)
			)
			(layer "B.Fab")
		)
		(fp_line
			(start 0.12065 0.3048)
			(end 0.67945 0.3048)
			(stroke
				(width 0.1)
				(type default)
			)
			(layer "B.Fab")
		)
		(fp_line
			(start 0.12065 0.2794)
			(end 0.12065 0.3048)
			(stroke
				(width 0.1)
				(type default)
			)
			(layer "B.Fab")
		)
		(fp_line
			(start 0.12065 -0.2794)
			(end -0.12065 -0.2794)
			(stroke
				(width 0.1)
				(type default)
			)
			(layer "B.Fab")
		)
		(fp_line
			(start 0.12065 -0.305054)
			(end 0.12065 -0.2794)
			(stroke
				(width 0.1)
				(type default)
			)
			(layer "B.Fab")
		)
		(fp_line
			(start -0.120396 0.3048)
			(end -0.120396 0.2794)
			(stroke
				(width 0.1)
				(type default)
			)
			(layer "B.Fab")
		)
		(fp_line
			(start -0.120396 0.2794)
			(end 0.12065 0.2794)
			(stroke
				(width 0.1)
				(type default)
			)
			(layer "B.Fab")
		)
		(fp_line
			(start -0.12065 -0.2794)
			(end -0.12065 -0.3048)
			(stroke
				(width 0.1)
				(type default)
			)
			(layer "B.Fab")
		)
		(fp_line
			(start -0.12065 -0.3048)
			(end -0.67945 -0.3048)
			(stroke
				(width 0.1)
				(type default)
			)
			(layer "B.Fab")
		)
		(fp_line
			(start -0.67945 0.3048)
			(end -0.120396 0.3048)
			(stroke
				(width 0.1)
				(type default)
			)
			(layer "B.Fab")
		)
		(fp_line
			(start -0.67945 -0.3048)
			(end -0.67945 0.3048)
			(stroke
				(width 0.1)
				(type default)
			)
			(layer "B.Fab")
		)
		(pad "1" smd circle
			(at 0.40005 0)
			(size 0 0)
			(layers "B.Cu" "B.Mask" "B.Paste")
			(net "P3V3_M2_0")
		)
		(pad "2" smd circle
			(at -0.40005 0)
			(size 0 0)
			(layers "B.Cu" "B.Mask" "B.Paste")
			(net "GND")
		)
	)
	(footprint ""
		(layer "B.Cu")
		(at 224.999042 -315.95568 -90)
		(property "Reference" "PC6531"
			(at 0 0 90)
			(layer "B.SilkS")
			(hide yes)
			(effects
				(font
					(size 1.27 1.27)
				)
				(justify mirror)
			)
		)
		(property "Value" ""
			(at 0 0 90)
			(layer "B.Fab")
			(effects
				(font
					(size 1.27 1.27)
				)
				(justify mirror)
			)
		)
		(duplicate_pad_numbers_are_jumpers no)
		(fp_line
			(start -1.524 0.762)
			(end 1.524 0.762)
			(stroke
				(width 0.1524)
				(type default)
			)
			(layer "B.SilkS")
		)
		(fp_line
			(start 1.524 0.762)
			(end 1.524 -0.762)
			(stroke
				(width 0.1524)
				(type default)
			)
			(layer "B.SilkS")
		)
		(fp_line
			(start -1.524 -0.762)
			(end -1.524 0.762)
			(stroke
				(width 0.1524)
				(type default)
			)
			(layer "B.SilkS")
		)
		(fp_line
			(start 1.524 -0.762)
			(end -1.524 -0.762)
			(stroke
				(width 0.1524)
				(type default)
			)
			(layer "B.SilkS")
		)
		(fp_line
			(start -1.1049 0.724916)
			(end -1.1049 -0.724916)
			(stroke
				(width 0.1)
				(type default)
			)
			(layer "B.Fab")
		)
		(fp_line
			(start 1.1049 0.724916)
			(end -1.1049 0.724916)
			(stroke
				(width 0.1)
				(type default)
			)
			(layer "B.Fab")
		)
		(fp_line
			(start -1.1049 -0.724916)
			(end 1.1049 -0.724916)
			(stroke
				(width 0.1)
				(type default)
			)
			(layer "B.Fab")
		)
		(fp_line
			(start 1.1049 -0.724916)
			(end 1.1049 0.724916)
			(stroke
				(width 0.1)
				(type default)
			)
			(layer "B.Fab")
		)
		(pad "1" smd rect
			(at 0.889 0 270)
			(size 1.016 1.27)
			(layers "B.Cu" "B.Mask" "B.Paste")
			(net "P1V8_CPU1_RT_1D")
		)
		(pad "2" smd rect
			(at -0.889 0 270)
			(size 1.016 1.27)
			(layers "B.Cu" "B.Mask" "B.Paste")
			(net "GND")
		)
	)
	(footprint ""
		(layer "B.Cu")
		(at 231.267 -218.059 90)
		(property "Reference" "R202"
			(at 0 0 90)
			(layer "B.SilkS")
			(hide yes)
			(effects
				(font
					(size 1.27 1.27)
				)
				(justify mirror)
			)
		)
		(property "Value" ""
			(at 0 0 90)
			(layer "B.Fab")
			(effects
				(font
					(size 1.27 1.27)
				)
				(justify mirror)
			)
		)
		(duplicate_pad_numbers_are_jumpers no)
		(fp_line
			(start 0.7874 -0.4064)
			(end -0.7874 -0.4064)
			(stroke
				(width 0.1524)
				(type default)
			)
			(layer "B.SilkS")
		)
		(fp_line
			(start -0.7874 -0.4064)
			(end -0.7874 0.4064)
			(stroke
				(width 0.1524)
				(type default)
			)
			(layer "B.SilkS")
		)
		(fp_line
			(start 0.7874 0.4064)
			(end 0.7874 -0.4064)
			(stroke
				(width 0.1524)
				(type default)
			)
			(layer "B.SilkS")
		)
		(fp_line
			(start -0.7874 0.4064)
			(end 0.7874 0.4064)
			(stroke
				(width 0.1524)
				(type default)
			)
			(layer "B.SilkS")
		)
		(fp_line
			(start 0.67945 -0.305054)
			(end 0.12065 -0.305054)
			(stroke
				(width 0.1)
				(type default)
			)
			(layer "B.Fab")
		)
		(fp_line
			(start 0.12065 -0.305054)
			(end 0.12065 -0.2794)
			(stroke
				(width 0.1)
				(type default)
			)
			(layer "B.Fab")
		)
		(fp_line
			(start -0.12065 -0.3048)
			(end -0.67945 -0.3048)
			(stroke
				(width 0.1)
				(type default)
			)
			(layer "B.Fab")
		)
		(fp_line
			(start -0.67945 -0.3048)
			(end -0.67945 0.3048)
			(stroke
				(width 0.1)
				(type default)
			)
			(layer "B.Fab")
		)
		(fp_line
			(start 0.12065 -0.2794)
			(end -0.12065 -0.2794)
			(stroke
				(width 0.1)
				(type default)
			)
			(layer "B.Fab")
		)
		(fp_line
			(start -0.12065 -0.2794)
			(end -0.12065 -0.3048)
			(stroke
				(width 0.1)
				(type default)
			)
			(layer "B.Fab")
		)
		(fp_line
			(start 0.12065 0.2794)
			(end 0.12065 0.3048)
			(stroke
				(width 0.1)
				(type default)
			)
			(layer "B.Fab")
		)
		(fp_line
			(start -0.120396 0.2794)
			(end 0.12065 0.2794)
			(stroke
				(width 0.1)
				(type default)
			)
			(layer "B.Fab")
		)
		(fp_line
			(start 0.67945 0.3048)
			(end 0.67945 -0.305054)
			(stroke
				(width 0.1)
				(type default)
			)
			(layer "B.Fab")
		)
		(fp_line
			(start 0.12065 0.3048)
			(end 0.67945 0.3048)
			(stroke
				(width 0.1)
				(type default)
			)
			(layer "B.Fab")
		)
		(fp_line
			(start -0.120396 0.3048)
			(end -0.120396 0.2794)
			(stroke
				(width 0.1)
				(type default)
			)
			(layer "B.Fab")
		)
		(fp_line
			(start -0.67945 0.3048)
			(end -0.120396 0.3048)
			(stroke
				(width 0.1)
				(type default)
			)
			(layer "B.Fab")
		)
		(pad "1" smd circle
			(at 0.40005 0 270)
			(size 0 0)
			(layers "B.Cu" "B.Mask" "B.Paste")
			(net "SMB_CPU0_CPU1_APML_BUF2_SCL_R1")
		)
		(pad "2" smd circle
			(at -0.40005 0 270)
			(size 0 0)
			(layers "B.Cu" "B.Mask" "B.Paste")
			(net "SMB_CPU0_CPU1_APML_BUF2_SCL_R2")
		)
	)
	(footprint ""
		(layer "B.Cu")
		(at 332.763876 -66.708782 90)
		(property "Reference" "R3090"
			(at 0 0 90)
			(layer "B.SilkS")
			(hide yes)
			(effects
				(font
					(size 1.27 1.27)
				)
				(justify mirror)
			)
		)
		(property "Value" ""
			(at 0 0 90)
			(layer "B.Fab")
			(effects
				(font
					(size 1.27 1.27)
				)
				(justify mirror)
			)
		)
		(duplicate_pad_numbers_are_jumpers no)
		(fp_line
			(start 0.7874 -0.4064)
			(end -0.7874 -0.4064)
			(stroke
				(width 0.1524)
				(type default)
			)
			(layer "B.SilkS")
		)
		(fp_line
			(start -0.7874 -0.4064)
			(end -0.7874 0.4064)
			(stroke
				(width 0.1524)
				(type default)
			)
			(layer "B.SilkS")
		)
		(fp_line
			(start 0.7874 0.4064)
			(end 0.7874 -0.4064)
			(stroke
				(width 0.1524)
				(type default)
			)
			(layer "B.SilkS")
		)
		(fp_line
			(start -0.7874 0.4064)
			(end 0.7874 0.4064)
			(stroke
				(width 0.1524)
				(type default)
			)
			(layer "B.SilkS")
		)
		(fp_line
			(start 0.67945 -0.305054)
			(end 0.12065 -0.305054)
			(stroke
				(width 0.1)
				(type default)
			)
			(layer "B.Fab")
		)
		(fp_line
			(start 0.12065 -0.305054)
			(end 0.12065 -0.2794)
			(stroke
				(width 0.1)
				(type default)
			)
			(layer "B.Fab")
		)
		(fp_line
			(start -0.12065 -0.3048)
			(end -0.67945 -0.3048)
			(stroke
				(width 0.1)
				(type default)
			)
			(layer "B.Fab")
		)
		(fp_line
			(start -0.67945 -0.3048)
			(end -0.67945 0.3048)
			(stroke
				(width 0.1)
				(type default)
			)
			(layer "B.Fab")
		)
		(fp_line
			(start 0.12065 -0.2794)
			(end -0.12065 -0.2794)
			(stroke
				(width 0.1)
				(type default)
			)
			(layer "B.Fab")
		)
		(fp_line
			(start -0.12065 -0.2794)
			(end -0.12065 -0.3048)
			(stroke
				(width 0.1)
				(type default)
			)
			(layer "B.Fab")
		)
		(fp_line
			(start 0.12065 0.2794)
			(end 0.12065 0.3048)
			(stroke
				(width 0.1)
				(type default)
			)
			(layer "B.Fab")
		)
		(fp_line
			(start -0.120396 0.2794)
			(end 0.12065 0.2794)
			(stroke
				(width 0.1)
				(type default)
			)
			(layer "B.Fab")
		)
		(fp_line
			(start 0.67945 0.3048)
			(end 0.67945 -0.305054)
			(stroke
				(width 0.1)
				(type default)
			)
			(layer "B.Fab")
		)
		(fp_line
			(start 0.12065 0.3048)
			(end 0.67945 0.3048)
			(stroke
				(width 0.1)
				(type default)
			)
			(layer "B.Fab")
		)
		(fp_line
			(start -0.120396 0.3048)
			(end -0.120396 0.2794)
			(stroke
				(width 0.1)
				(type default)
			)
			(layer "B.Fab")
		)
		(fp_line
			(start -0.67945 0.3048)
			(end -0.120396 0.3048)
			(stroke
				(width 0.1)
				(type default)
			)
			(layer "B.Fab")
		)
		(pad "1" smd circle
			(at 0.40005 0 270)
			(size 0 0)
			(layers "B.Cu" "B.Mask" "B.Paste")
			(net "LED_PWRGD_PVDD11_S3_P0_R")
		)
		(pad "2" smd circle
			(at -0.40005 0 270)
			(size 0 0)
			(layers "B.Cu" "B.Mask" "B.Paste")
			(net "P3V3_AUX")
		)
	)
	(footprint ""
		(layer "B.Cu")
		(at 108.15828 -410.252672)
		(property "Reference" "C75"
			(at 0 0 0)
			(layer "B.SilkS")
			(hide yes)
			(effects
				(font
					(size 1.27 1.27)
				)
				(justify mirror)
			)
		)
		(property "Value" ""
			(at 0 0 0)
			(layer "B.Fab")
			(effects
				(font
					(size 1.27 1.27)
				)
				(justify mirror)
			)
		)
		(duplicate_pad_numbers_are_jumpers no)
		(fp_line
			(start -0.7874 -0.4064)
			(end -0.7874 0.4064)
			(stroke
				(width 0.1524)
				(type default)
			)
			(layer "B.SilkS")
		)
		(fp_line
			(start -0.7874 0.4064)
			(end 0.7874 0.4064)
			(stroke
				(width 0.1524)
				(type default)
			)
			(layer "B.SilkS")
		)
		(fp_line
			(start 0.7874 -0.4064)
			(end -0.7874 -0.4064)
			(stroke
				(width 0.1524)
				(type default)
			)
			(layer "B.SilkS")
		)
		(fp_line
			(start 0.7874 0.4064)
			(end 0.7874 -0.4064)
			(stroke
				(width 0.1524)
				(type default)
			)
			(layer "B.SilkS")
		)
		(fp_line
			(start -0.67945 -0.3048)
			(end -0.67945 0.3048)
			(stroke
				(width 0.1)
				(type default)
			)
			(layer "B.Fab")
		)
		(fp_line
			(start -0.67945 0.3048)
			(end -0.120396 0.3048)
			(stroke
				(width 0.1)
				(type default)
			)
			(layer "B.Fab")
		)
		(fp_line
			(start -0.12065 -0.3048)
			(end -0.67945 -0.3048)
			(stroke
				(width 0.1)
				(type default)
			)
			(layer "B.Fab")
		)
		(fp_line
			(start -0.12065 -0.2794)
			(end -0.12065 -0.3048)
			(stroke
				(width 0.1)
				(type default)
			)
			(layer "B.Fab")
		)
		(fp_line
			(start -0.120396 0.2794)
			(end 0.12065 0.2794)
			(stroke
				(width 0.1)
				(type default)
			)
			(layer "B.Fab")
		)
		(fp_line
			(start -0.120396 0.3048)
			(end -0.120396 0.2794)
			(stroke
				(width 0.1)
				(type default)
			)
			(layer "B.Fab")
		)
		(fp_line
			(start 0.12065 -0.305054)
			(end 0.12065 -0.2794)
			(stroke
				(width 0.1)
				(type default)
			)
			(layer "B.Fab")
		)
		(fp_line
			(start 0.12065 -0.2794)
			(end -0.12065 -0.2794)
			(stroke
				(width 0.1)
				(type default)
			)
			(layer "B.Fab")
		)
		(fp_line
			(start 0.12065 0.2794)
			(end 0.12065 0.3048)
			(stroke
				(width 0.1)
				(type default)
			)
			(layer "B.Fab")
		)
		(fp_line
			(start 0.12065 0.3048)
			(end 0.67945 0.3048)
			(stroke
				(width 0.1)
				(type default)
			)
			(layer "B.Fab")
		)
		(fp_line
			(start 0.67945 -0.305054)
			(end 0.12065 -0.305054)
			(stroke
				(width 0.1)
				(type default)
			)
			(layer "B.Fab")
		)
		(fp_line
			(start 0.67945 0.3048)
			(end 0.67945 -0.305054)
			(stroke
				(width 0.1)
				(type default)
			)
			(layer "B.Fab")
		)
		(pad "1" smd circle
			(at 0.40005 0 180)
			(size 0 0)
			(layers "B.Cu" "B.Mask" "B.Paste")
			(net "P3V3_9ZXL045_P1_VDD")
		)
		(pad "2" smd circle
			(at -0.40005 0 180)
			(size 0 0)
			(layers "B.Cu" "B.Mask" "B.Paste")
			(net "GND")
		)
	)
)
